# BASEBOARD_FAB2 (Tioga Pass) — schematic netlist excerpt (pin names and nets, part order shuffled) for the footprints in the layout excerpt that follows; sources: Cadence DE-HDL packaged netlist, KiCad conversion of Wiwynn_Tioga_Pass_MB.brd

C3N33  CAP  10UF 16V 10% X6S  pkg 0805  page 212 : A = VR_FET_SW_P12V_STBY_PVCCIO_CPU0 ; B = GND
R25W125  RES  150.0 1% CHIP  pkg 0402  page 144 : A = BMC_VGA_RED ; B = GND
C3T7  CAP  47UF 4V 20% X6S  pkg 0805  page 231 : A = PVPP_ABC ; B = GND

(kicad_pcb
	(version 20260206)
	(generator "pcbnew")
	(generator_version "10.0")
	(general
		(thickness 1.6)
		(legacy_teardrops no)
	)
	(paper "A4")
	(title_block
		(title "Wiwynn_Tioga_Pass_MB.brd")
		(comment 1 "Tioga Pass / footprints 3062-3064 of 4770")
	)
	(layers
		(0 "F.Cu" signal "TOP")
		(4 "In1.Cu" signal "L2GND")
		(6 "In2.Cu" signal "L3")
		(8 "In3.Cu" signal "L4GND")
		(10 "In4.Cu" signal "L5")
		(12 "In5.Cu" signal "L6GND")
		(14 "In6.Cu" signal "L7VCC")
		(16 "In7.Cu" signal "L8VCC")
		(18 "In8.Cu" signal "L9GND")
		(20 "In9.Cu" signal "L10")
		(22 "In10.Cu" signal "L11GND")
		(24 "In11.Cu" signal "L12")
		(26 "In12.Cu" signal "L13GND")
		(2 "B.Cu" signal "BOTTOM")
		(9 "F.Adhes" user "F.Adhesive")
		(11 "B.Adhes" user "B.Adhesive")
		(13 "F.Paste" user "Package Geometry/Pastemask Top")
		(15 "B.Paste" user "Package Geometry/Pastemask Bottom")
		(5 "F.SilkS" user "Ref Des/Silkscreen Top")
		(7 "B.SilkS" user "Ref Des/Silkscreen Bottom")
		(1 "F.Mask" user "Board Geometry/Soldermask Top")
		(3 "B.Mask" user "Board Geometry/Soldermask Bottom")
		(17 "Dwgs.User" user "User.Drawings")
		(19 "Cmts.User" user "User.Comments")
		(21 "Eco1.User" user "User.Eco1")
		(23 "Eco2.User" user "User.Eco2")
		(25 "Edge.Cuts" user "Board Geometry/Outline")
		(27 "Margin" user)
		(31 "F.CrtYd" user "Package Geometry/Place Bound Top")
		(29 "B.CrtYd" user "Package Geometry/Place Bound Bottom")
		(35 "F.Fab" user "Ref Des/Assembly Top")
		(33 "B.Fab" user "Ref Des/Assembly Bottom")
	)
	(footprint ""
		(layer "B.Cu")
		(at 416.9664 -26.035)
		(property "Reference" "R25W125"
			(at 0.8382 -0.67818 0)
			(unlocked yes)
			(layer "B.SilkS")
			(effects
				(font
					(size 0.4064 0.254)
					(thickness 0.1524)
				)
				(justify left mirror)
			)
		)
		(property "Value" ""
			(at 0 0 0)
			(layer "B.Fab")
			(effects
				(font
					(size 1.27 1.27)
				)
				(justify mirror)
			)
		)
		(duplicate_pad_numbers_are_jumpers no)
		(fp_poly
			(pts
				(xy 0.2794 -0.1016) (xy -0.2794 -0.1016) (xy -0.2794 0.9906) (xy 0.2794 0.9906)
			)
			(stroke
				(width 0)
				(type default)
			)
			(fill no)
			(layer "B.CrtYd")
		)
		(fp_line
			(start -0.2794 -0.1016)
			(end 0.2794 -0.1016)
			(stroke
				(width 0.1)
				(type default)
			)
			(layer "B.Fab")
		)
		(fp_line
			(start -0.2794 0.9906)
			(end -0.2794 -0.1016)
			(stroke
				(width 0.1)
				(type default)
			)
			(layer "B.Fab")
		)
		(fp_line
			(start 0.2794 -0.1016)
			(end 0.2794 0.9906)
			(stroke
				(width 0.1)
				(type default)
			)
			(layer "B.Fab")
		)
		(fp_line
			(start 0.2794 0.9906)
			(end -0.2794 0.9906)
			(stroke
				(width 0.1)
				(type default)
			)
			(layer "B.Fab")
		)
		(pad "1" smd rect
			(at 0 0 180)
			(size 0.508 0.508)
			(layers "B.Cu" "B.Mask" "B.Paste")
			(net "BMC_VGA_RED")
		)
		(pad "2" smd rect
			(at 0 0.889 180)
			(size 0.508 0.508)
			(layers "B.Cu" "B.Mask" "B.Paste")
			(net "GND")
		)
		(zone
			(layer "B.Cu")
			(hatch none 0.5)
			(connect_pads
				(clearance 0)
			)
			(min_thickness 0.25)
			(keepout
				(tracks allowed)
				(vias not_allowed)
				(pads allowed)
				(copperpour not_allowed)
				(footprints allowed)
			)
			(placement
				(enabled no)
				(sheetname "")
			)
			(fill
				(thermal_gap 0.5)
				(thermal_bridge_width 0.5)
				(island_removal_mode 0)
			)
			(polygon
				(pts
					(xy 417.2204 -25.781) (xy 416.7124 -25.781) (xy 416.7124 -25.4) (xy 417.2204 -25.4)
				)
			)
		)
		(zone
			(layer "B.Cu")
			(hatch none 0.5)
			(connect_pads
				(clearance 0)
			)
			(min_thickness 0.25)
			(keepout
				(tracks not_allowed)
				(vias allowed)
				(pads allowed)
				(copperpour not_allowed)
				(footprints allowed)
			)
			(placement
				(enabled no)
				(sheetname "")
			)
			(fill
				(thermal_gap 0.5)
				(thermal_bridge_width 0.5)
				(island_removal_mode 0)
			)
			(polygon
				(pts
					(xy 417.2204 -25.4) (xy 416.7124 -25.4) (xy 416.7124 -25.781) (xy 417.2204 -25.781)
				)
			)
		)
	)
	(footprint ""
		(layer "B.Cu")
		(at 333.6798 -30.3403 90)
		(property "Reference" "C3T7"
			(at 0 0 90)
			(layer "B.SilkS")
			(hide yes)
			(effects
				(font
					(size 1.27 1.27)
				)
				(justify mirror)
			)
		)
		(property "Value" ""
			(at 0 0 90)
			(layer "B.Fab")
			(effects
				(font
					(size 1.27 1.27)
				)
				(justify mirror)
			)
		)
		(duplicate_pad_numbers_are_jumpers no)
		(fp_rect
			(start -0.7239 -0.2159)
			(end 0.7239 1.9939)
			(stroke
				(width 0)
				(type default)
			)
			(fill no)
			(layer "B.CrtYd")
		)
		(fp_line
			(start 0.7239 -0.2159)
			(end 0.7239 1.9939)
			(stroke
				(width 0.1)
				(type default)
			)
			(layer "B.Fab")
		)
		(fp_line
			(start -0.7239 -0.2159)
			(end 0.7239 -0.2159)
			(stroke
				(width 0.1)
				(type default)
			)
			(layer "B.Fab")
		)
		(fp_line
			(start 0.7239 1.9939)
			(end -0.7239 1.9939)
			(stroke
				(width 0.1)
				(type default)
			)
			(layer "B.Fab")
		)
		(fp_line
			(start -0.7239 1.9939)
			(end -0.7239 -0.2159)
			(stroke
				(width 0.1)
				(type default)
			)
			(layer "B.Fab")
		)
		(pad "1" smd rect
			(at 0 0 270)
			(size 1.27 1.016)
			(layers "B.Cu" "B.Mask" "B.Paste")
			(net "PVPP_ABC")
		)
		(pad "2" smd rect
			(at 0 1.778 270)
			(size 1.27 1.016)
			(layers "B.Cu" "B.Mask" "B.Paste")
			(net "GND")
		)
		(zone
			(layer "B.Cu")
			(hatch none 0.5)
			(connect_pads
				(clearance 0)
			)
			(min_thickness 0.25)
			(keepout
				(tracks not_allowed)
				(vias allowed)
				(pads allowed)
				(copperpour not_allowed)
				(footprints allowed)
			)
			(placement
				(enabled no)
				(sheetname "")
			)
			(fill
				(thermal_gap 0.5)
				(thermal_bridge_width 0.5)
				(island_removal_mode 0)
			)
			(polygon
				(pts
					(xy 334.1878 -29.7053) (xy 334.9498 -29.7053) (xy 334.9498 -30.9753) (xy 334.1878 -30.9753)
				)
			)
		)
	)
	(footprint ""
		(layer "B.Cu")
		(at 348.1832 -96.5708 -90)
		(property "Reference" "C3N33"
			(at 0 0 90)
			(layer "B.SilkS")
			(hide yes)
			(effects
				(font
					(size 1.27 1.27)
				)
				(justify mirror)
			)
		)
		(property "Value" ""
			(at 0 0 90)
			(layer "B.Fab")
			(effects
				(font
					(size 1.27 1.27)
				)
				(justify mirror)
			)
		)
		(duplicate_pad_numbers_are_jumpers no)
		(fp_poly
			(pts
				(xy 0.7239 -0.2159) (xy -0.7239 -0.2159) (xy -0.7239 1.9939) (xy 0.7239 1.9939)
			)
			(stroke
				(width 0)
				(type default)
			)
			(fill no)
			(layer "B.CrtYd")
		)
		(fp_line
			(start -0.7239 1.9939)
			(end -0.7239 -0.2159)
			(stroke
				(width 0.1)
				(type default)
			)
			(layer "B.Fab")
		)
		(fp_line
			(start 0.7239 1.9939)
			(end -0.7239 1.9939)
			(stroke
				(width 0.1)
				(type default)
			)
			(layer "B.Fab")
		)
		(fp_line
			(start -0.7239 -0.2159)
			(end 0.7239 -0.2159)
			(stroke
				(width 0.1)
				(type default)
			)
			(layer "B.Fab")
		)
		(fp_line
			(start 0.7239 -0.2159)
			(end 0.7239 1.9939)
			(stroke
				(width 0.1)
				(type default)
			)
			(layer "B.Fab")
		)
		(pad "1" smd rect
			(at 0 0 90)
			(size 1.27 1.016)
			(layers "B.Cu" "B.Mask" "B.Paste")
			(net "VR_FET_SW_P12V_STBY_PVCCIO_CPU0")
		)
		(pad "2" smd rect
			(at 0 1.778 90)
			(size 1.27 1.016)
			(layers "B.Cu" "B.Mask" "B.Paste")
			(net "GND")
		)
		(zone
			(layer "B.Cu")
			(hatch none 0.5)
			(connect_pads
				(clearance 0)
			)
			(min_thickness 0.25)
			(keepout
				(tracks not_allowed)
				(vias allowed)
				(pads allowed)
				(copperpour not_allowed)
				(footprints allowed)
			)
			(placement
				(enabled no)
				(sheetname "")
			)
			(fill
				(thermal_gap 0.5)
				(thermal_bridge_width 0.5)
				(island_removal_mode 0)
			)
			(polygon
				(pts
					(xy 347.6752 -95.9358) (xy 347.6752 -97.2058) (xy 346.9132 -97.2058) (xy 346.9132 -95.9358)
				)
			)
		)
	)
)
